# BASEBOARD_FAB2 (Tioga Pass) — schematic netlist excerpt (pin names and nets, part order shuffled) for the footprints in the layout excerpt that follows; sources: Cadence DE-HDL packaged netlist, KiCad conversion of Wiwynn_Tioga_Pass_MB.brd

R25W12  120R2F-GP  1%  pkg RCL_GP  page 151 : \1\ = GND ; \2\ = BMC_M_A0
R2U12  RES  20.0 1% EMPTY  pkg 0402  page 138 : A = SMB_LAN_STBY_LVC3_SDA ; B = SMB_OCP_FRU_STBY_LVC3_SDA
C2N26  CAP_A  1.0UF 6.3V 10% X6S  pkg 0402V  page 130 : A = P3V3_STBY ; B = GND

(kicad_pcb
	(version 20260206)
	(generator "pcbnew")
	(generator_version "10.0")
	(general
		(thickness 1.6)
		(legacy_teardrops no)
	)
	(paper "A4")
	(title_block
		(title "Wiwynn_Tioga_Pass_MB.brd")
		(comment 1 "Tioga Pass / footprints 3834-3836 of 4770")
	)
	(layers
		(0 "F.Cu" signal "TOP")
		(4 "In1.Cu" signal "L2GND")
		(6 "In2.Cu" signal "L3")
		(8 "In3.Cu" signal "L4GND")
		(10 "In4.Cu" signal "L5")
		(12 "In5.Cu" signal "L6GND")
		(14 "In6.Cu" signal "L7VCC")
		(16 "In7.Cu" signal "L8VCC")
		(18 "In8.Cu" signal "L9GND")
		(20 "In9.Cu" signal "L10")
		(22 "In10.Cu" signal "L11GND")
		(24 "In11.Cu" signal "L12")
		(26 "In12.Cu" signal "L13GND")
		(2 "B.Cu" signal "BOTTOM")
		(9 "F.Adhes" user "F.Adhesive")
		(11 "B.Adhes" user "B.Adhesive")
		(13 "F.Paste" user "Package Geometry/Pastemask Top")
		(15 "B.Paste" user "Package Geometry/Pastemask Bottom")
		(5 "F.SilkS" user "Ref Des/Silkscreen Top")
		(7 "B.SilkS" user "Ref Des/Silkscreen Bottom")
		(1 "F.Mask" user "Board Geometry/Soldermask Top")
		(3 "B.Mask" user "Board Geometry/Soldermask Bottom")
		(17 "Dwgs.User" user "User.Drawings")
		(19 "Cmts.User" user "User.Comments")
		(21 "Eco1.User" user "User.Eco1")
		(23 "Eco2.User" user "User.Eco2")
		(25 "Edge.Cuts" user "Board Geometry/Outline")
		(27 "Margin" user)
		(31 "F.CrtYd" user "Package Geometry/Place Bound Top")
		(29 "B.CrtYd" user "Package Geometry/Place Bound Bottom")
		(35 "F.Fab" user "Ref Des/Assembly Top")
		(33 "B.Fab" user "Ref Des/Assembly Bottom")
	)
	(footprint ""
		(layer "B.Cu")
		(at 394.589 -85.9155)
		(property "Reference" "R2U12"
			(at 0 0 0)
			(layer "B.SilkS")
			(hide yes)
			(effects
				(font
					(size 1.27 1.27)
				)
				(justify mirror)
			)
		)
		(property "Value" ""
			(at 0 0 0)
			(layer "B.Fab")
			(effects
				(font
					(size 1.27 1.27)
				)
				(justify mirror)
			)
		)
		(duplicate_pad_numbers_are_jumpers no)
		(fp_poly
			(pts
				(xy 0.2794 -0.1016) (xy -0.2794 -0.1016) (xy -0.2794 0.9906) (xy 0.2794 0.9906)
			)
			(stroke
				(width 0)
				(type default)
			)
			(fill no)
			(layer "B.CrtYd")
		)
		(fp_line
			(start -0.2794 -0.1016)
			(end 0.2794 -0.1016)
			(stroke
				(width 0.1)
				(type default)
			)
			(layer "B.Fab")
		)
		(fp_line
			(start -0.2794 0.9906)
			(end -0.2794 -0.1016)
			(stroke
				(width 0.1)
				(type default)
			)
			(layer "B.Fab")
		)
		(fp_line
			(start 0.2794 -0.1016)
			(end 0.2794 0.9906)
			(stroke
				(width 0.1)
				(type default)
			)
			(layer "B.Fab")
		)
		(fp_line
			(start 0.2794 0.9906)
			(end -0.2794 0.9906)
			(stroke
				(width 0.1)
				(type default)
			)
			(layer "B.Fab")
		)
		(pad "1" smd rect
			(at 0 0 180)
			(size 0.508 0.508)
			(layers "B.Cu" "B.Mask" "B.Paste")
			(net "SMB_LAN_STBY_LVC3_SDA")
		)
		(pad "2" smd rect
			(at 0 0.889 180)
			(size 0.508 0.508)
			(layers "B.Cu" "B.Mask" "B.Paste")
			(net "SMB_OCP_FRU_STBY_LVC3_SDA")
		)
		(zone
			(layer "B.Cu")
			(hatch none 0.5)
			(connect_pads
				(clearance 0)
			)
			(min_thickness 0.25)
			(keepout
				(tracks allowed)
				(vias not_allowed)
				(pads allowed)
				(copperpour not_allowed)
				(footprints allowed)
			)
			(placement
				(enabled no)
				(sheetname "")
			)
			(fill
				(thermal_gap 0.5)
				(thermal_bridge_width 0.5)
				(island_removal_mode 0)
			)
			(polygon
				(pts
					(xy 394.843 -85.6615) (xy 394.335 -85.6615) (xy 394.335 -85.2805) (xy 394.843 -85.2805)
				)
			)
		)
		(zone
			(layer "B.Cu")
			(hatch none 0.5)
			(connect_pads
				(clearance 0)
			)
			(min_thickness 0.25)
			(keepout
				(tracks not_allowed)
				(vias allowed)
				(pads allowed)
				(copperpour not_allowed)
				(footprints allowed)
			)
			(placement
				(enabled no)
				(sheetname "")
			)
			(fill
				(thermal_gap 0.5)
				(thermal_bridge_width 0.5)
				(island_removal_mode 0)
			)
			(polygon
				(pts
					(xy 394.843 -85.2805) (xy 394.335 -85.2805) (xy 394.335 -85.6615) (xy 394.843 -85.6615)
				)
			)
		)
	)
	(footprint ""
		(layer "B.Cu")
		(at 400.7485 -106.172 -90)
		(property "Reference" "C2N26"
			(at 0 0 90)
			(layer "B.SilkS")
			(hide yes)
			(effects
				(font
					(size 1.27 1.27)
				)
				(justify mirror)
			)
		)
		(property "Value" ""
			(at 0 0 90)
			(layer "B.Fab")
			(effects
				(font
					(size 1.27 1.27)
				)
				(justify mirror)
			)
		)
		(duplicate_pad_numbers_are_jumpers no)
		(fp_poly
			(pts
				(xy -0.3048 -0.1016) (xy -0.3048 0.9906) (xy 0.3048 0.9906) (xy 0.3048 -0.1016)
			)
			(stroke
				(width 0)
				(type default)
			)
			(fill no)
			(layer "B.CrtYd")
		)
		(fp_line
			(start -0.3048 0.9906)
			(end -0.3048 -0.1016)
			(stroke
				(width 0.1)
				(type default)
			)
			(layer "B.Fab")
		)
		(fp_line
			(start 0.3048 0.9906)
			(end -0.3048 0.9906)
			(stroke
				(width 0.1)
				(type default)
			)
			(layer "B.Fab")
		)
		(fp_line
			(start -0.3048 -0.1016)
			(end 0.3048 -0.1016)
			(stroke
				(width 0.1)
				(type default)
			)
			(layer "B.Fab")
		)
		(fp_line
			(start 0.3048 -0.1016)
			(end 0.3048 0.9906)
			(stroke
				(width 0.1)
				(type default)
			)
			(layer "B.Fab")
		)
		(pad "1" smd rect
			(at 0 0 90)
			(size 0.508 0.508)
			(layers "B.Cu" "B.Mask" "B.Paste")
			(net "P3V3_STBY")
		)
		(pad "2" smd rect
			(at 0 0.889 90)
			(size 0.508 0.508)
			(layers "B.Cu" "B.Mask" "B.Paste")
			(net "GND")
		)
		(zone
			(layer "B.Cu")
			(hatch none 0.5)
			(connect_pads
				(clearance 0)
			)
			(min_thickness 0.25)
			(keepout
				(tracks not_allowed)
				(vias allowed)
				(pads allowed)
				(copperpour not_allowed)
				(footprints allowed)
			)
			(placement
				(enabled no)
				(sheetname "")
			)
			(fill
				(thermal_gap 0.5)
				(thermal_bridge_width 0.5)
				(island_removal_mode 0)
			)
			(polygon
				(pts
					(xy 400.1135 -105.918) (xy 400.1135 -106.426) (xy 400.4945 -106.426) (xy 400.4945 -105.918)
				)
			)
		)
		(zone
			(layer "B.Cu")
			(hatch none 0.5)
			(connect_pads
				(clearance 0)
			)
			(min_thickness 0.25)
			(keepout
				(tracks allowed)
				(vias not_allowed)
				(pads allowed)
				(copperpour not_allowed)
				(footprints allowed)
			)
			(placement
				(enabled no)
				(sheetname "")
			)
			(fill
				(thermal_gap 0.5)
				(thermal_bridge_width 0.5)
				(island_removal_mode 0)
			)
			(polygon
				(pts
					(xy 400.4945 -105.918) (xy 400.4945 -106.426) (xy 400.1135 -106.426) (xy 400.1135 -105.918)
				)
			)
		)
	)
	(footprint ""
		(layer "B.Cu")
		(at 446.381632 -37.032692 90)
		(property "Reference" "R25W12"
			(at 0 0 90)
			(layer "B.SilkS")
			(hide yes)
			(effects
				(font
					(size 1.27 1.27)
				)
				(justify mirror)
			)
		)
		(property "Value" "*"
			(at -0.064008 -4.108196 90)
			(unlocked yes)
			(layer "B.Fab")
			(hide yes)
			(effects
				(font
					(size 1.27 1.016)
					(thickness 0.1524)
				)
				(justify mirror)
			)
		)
		(property "Device Type" "120R2F-GP_RCL_GP-120R2F-GP,64.A"
			(at -0.064008 -5.632196 90)
			(unlocked yes)
			(layer "B.Fab")
			(hide yes)
			(effects
				(font
					(size 1.27 1.016)
					(thickness 0.1524)
				)
				(justify mirror)
			)
		)
		(duplicate_pad_numbers_are_jumpers no)
		(fp_line
			(start 0.508 -0.9398)
			(end 0.508 0.9398)
			(stroke
				(width 0.1524)
				(type default)
			)
			(layer "B.SilkS")
		)
		(fp_line
			(start -0.508 -0.9398)
			(end 0.508 -0.9398)
			(stroke
				(width 0.1524)
				(type default)
			)
			(layer "B.SilkS")
		)
		(fp_rect
			(start 0.508 0.9398)
			(end -0.508 -0.9398)
			(stroke
				(width 0)
				(type default)
			)
			(fill no)
			(layer "B.CrtYd")
		)
		(fp_rect
			(start 0.508 0.9398)
			(end -0.508 -0.9398)
			(stroke
				(width 0)
				(type default)
			)
			(fill no)
			(layer "B.Fab")
		)
		(pad "1" smd custom
			(at 0 -0.4445 270)
			(size 0.1397 0.1397)
			(layers "B.Cu" "B.Mask" "B.Paste")
			(net "GND")
			(options
				(clearance outline)
				(anchor circle)
			)
			(primitives
				(gr_poly
					(pts
						(arc
							(start -0.1778 0.2794)
							(mid -0.249642 0.249642)
							(end -0.2794 0.1778)
						)
						(arc
							(start -0.2794 -0.1778)
							(mid -0.249642 -0.249642)
							(end -0.1778 -0.2794)
						)
						(arc
							(start 0.1778 -0.2794)
							(mid 0.249642 -0.249642)
							(end 0.2794 -0.1778)
						)
						(arc
							(start 0.2794 0.1778)
							(mid 0.249642 0.249642)
							(end 0.1778 0.2794)
						)
					)
					(width 0)
					(fill yes)
				)
			)
		)
		(pad "2" smd custom
			(at 0 0.4445 270)
			(size 0.1397 0.1397)
			(layers "B.Cu" "B.Mask" "B.Paste")
			(net "BMC_M_A0")
			(options
				(clearance outline)
				(anchor circle)
			)
			(primitives
				(gr_poly
					(pts
						(arc
							(start -0.1778 0.2794)
							(mid -0.249642 0.249642)
							(end -0.2794 0.1778)
						)
						(arc
							(start -0.2794 -0.1778)
							(mid -0.249642 -0.249642)
							(end -0.1778 -0.2794)
						)
						(arc
							(start 0.1778 -0.2794)
							(mid 0.249642 -0.249642)
							(end 0.2794 -0.1778)
						)
						(arc
							(start 0.2794 0.1778)
							(mid 0.249642 0.249642)
							(end 0.1778 0.2794)
						)
					)
					(width 0)
					(fill yes)
				)
			)
		)
	)
)
